(kicad_pcb
	(version 20260206)
	(generator "pcbnew")
	(generator_version "10.0")
	(general
		(thickness 1.6)
		(legacy_teardrops no)
	)
	(paper "A4")
	(title_block
		(title "baseboard — 13948-1b.1110WZS1818.brd")
		(comment 1 "Honey Badger (Wiwynn) / footprints 1306-1312 of 2523")
	)
	(layers
		(0 "F.Cu" signal "TOP")
		(4 "In1.Cu" signal "L2GND")
		(6 "In2.Cu" signal "L3")
		(8 "In3.Cu" signal "L4VCC")
		(10 "In4.Cu" signal "L5VCC")
		(12 "In5.Cu" signal "L6")
		(14 "In6.Cu" signal "L7GND")
		(2 "B.Cu" signal "BOTTOM")
		(9 "F.Adhes" user "F.Adhesive")
		(11 "B.Adhes" user "B.Adhesive")
		(13 "F.Paste" user "Package Geometry/Pastemask Top")
		(15 "B.Paste" user "Package Geometry/Pastemask Bottom")
		(5 "F.SilkS" user "Ref Des/Silkscreen Top")
		(7 "B.SilkS" user "Ref Des/Silkscreen Bottom")
		(1 "F.Mask" user "Board Geometry/Soldermask Top")
		(3 "B.Mask" user "Board Geometry/Soldermask Bottom")
		(17 "Dwgs.User" user "User.Drawings")
		(19 "Cmts.User" user "User.Comments")
		(21 "Eco1.User" user "User.Eco1")
		(23 "Eco2.User" user "User.Eco2")
		(25 "Edge.Cuts" user "Board Geometry/Outline")
		(27 "Margin" user)
		(31 "F.CrtYd" user "Package Geometry/Place Bound Top")
		(29 "B.CrtYd" user "Package Geometry/Place Bound Bottom")
		(35 "F.Fab" user "Ref Des/Assembly Top")
		(33 "B.Fab" user "Ref Des/Assembly Bottom")
	)
	(footprint ""
		(layer "F.Cu")
		(at 35.383216 -206.43088 90)
		(property "Reference" "R572"
			(at 0 0 90)
			(layer "F.SilkS")
			(hide yes)
			(effects
				(font
					(size 1.27 1.27)
				)
			)
		)
		(property "Value" "0R2J-2-GP"
			(at 0.064008 -3.993896 90)
			(unlocked yes)
			(layer "F.Fab")
			(hide yes)
			(effects
				(font
					(size 1.016 1.016)
					(thickness 0.1524)
				)
			)
		)
		(property "Device Type" "R402H16"
			(at 0.064008 -5.517896 90)
			(unlocked yes)
			(layer "F.Fab")
			(hide yes)
			(effects
				(font
					(size 1.016 1.016)
					(thickness 0.1524)
				)
			)
		)
		(duplicate_pad_numbers_are_jumpers no)
		(fp_line
			(start 0.508 -0.9398)
			(end -0.508 -0.9398)
			(stroke
				(width 0.1524)
				(type default)
			)
			(layer "F.SilkS")
		)
		(fp_line
			(start -0.508 -0.9398)
			(end -0.508 0.9398)
			(stroke
				(width 0.1524)
				(type default)
			)
			(layer "F.SilkS")
		)
		(fp_rect
			(start -0.508 0.9398)
			(end 0.508 -0.9398)
			(stroke
				(width 0)
				(type default)
			)
			(fill no)
			(layer "F.CrtYd")
		)
		(fp_rect
			(start -0.508 0.9398)
			(end 0.508 -0.9398)
			(stroke
				(width 0)
				(type default)
			)
			(fill no)
			(layer "F.Fab")
		)
		(pad "1" smd custom
			(at 0 -0.4445 90)
			(size 0.1397 0.1397)
			(layers "F.Cu" "F.Mask" "F.Paste")
			(net "VOL_SEN_SCL_U17")
			(options
				(clearance outline)
				(anchor circle)
			)
			(primitives
				(gr_poly
					(pts
						(arc
							(start -0.1778 -0.2794)
							(mid -0.249642 -0.249642)
							(end -0.2794 -0.1778)
						)
						(arc
							(start -0.2794 0.1778)
							(mid -0.249642 0.249642)
							(end -0.1778 0.2794)
						)
						(arc
							(start 0.1778 0.2794)
							(mid 0.249642 0.249642)
							(end 0.2794 0.1778)
						)
						(arc
							(start 0.2794 -0.1778)
							(mid 0.249642 -0.249642)
							(end 0.1778 -0.2794)
						)
					)
					(width 0)
					(fill yes)
				)
			)
		)
		(pad "2" smd custom
			(at 0 0.4445 90)
			(size 0.1397 0.1397)
			(layers "F.Cu" "F.Mask" "F.Paste")
			(net "BMC_I2C_A_SCL")
			(options
				(clearance outline)
				(anchor circle)
			)
			(primitives
				(gr_poly
					(pts
						(arc
							(start -0.1778 -0.2794)
							(mid -0.249642 -0.249642)
							(end -0.2794 -0.1778)
						)
						(arc
							(start -0.2794 0.1778)
							(mid -0.249642 0.249642)
							(end -0.1778 0.2794)
						)
						(arc
							(start 0.1778 0.2794)
							(mid 0.249642 0.249642)
							(end 0.2794 0.1778)
						)
						(arc
							(start 0.2794 -0.1778)
							(mid 0.249642 -0.249642)
							(end 0.1778 -0.2794)
						)
					)
					(width 0)
					(fill yes)
				)
			)
		)
	)
	(footprint ""
		(layer "F.Cu")
		(at 312.547 -193.548 90)
		(property "Reference" "R801"
			(at 0 0 90)
			(layer "F.SilkS")
			(hide yes)
			(effects
				(font
					(size 1.27 1.27)
				)
			)
		)
		(property "Value" "4K7R2F-GP"
			(at 0.064008 -3.993896 90)
			(unlocked yes)
			(layer "F.Fab")
			(hide yes)
			(effects
				(font
					(size 1.016 1.016)
					(thickness 0.1524)
				)
			)
		)
		(property "Device Type" "R402H16"
			(at 0.064008 -5.517896 90)
			(unlocked yes)
			(layer "F.Fab")
			(hide yes)
			(effects
				(font
					(size 1.016 1.016)
					(thickness 0.1524)
				)
			)
		)
		(duplicate_pad_numbers_are_jumpers no)
		(fp_line
			(start 0.508 -0.9398)
			(end -0.508 -0.9398)
			(stroke
				(width 0.1524)
				(type default)
			)
			(layer "F.SilkS")
		)
		(fp_line
			(start -0.508 -0.9398)
			(end -0.508 0.9398)
			(stroke
				(width 0.1524)
				(type default)
			)
			(layer "F.SilkS")
		)
		(fp_rect
			(start -0.508 0.9398)
			(end 0.508 -0.9398)
			(stroke
				(width 0)
				(type default)
			)
			(fill no)
			(layer "F.CrtYd")
		)
		(fp_rect
			(start -0.508 0.9398)
			(end 0.508 -0.9398)
			(stroke
				(width 0)
				(type default)
			)
			(fill no)
			(layer "F.Fab")
		)
		(pad "1" smd custom
			(at 0 -0.4445 90)
			(size 0.1397 0.1397)
			(layers "F.Cu" "F.Mask" "F.Paste")
			(net "P3V3_STBY")
			(options
				(clearance outline)
				(anchor circle)
			)
			(primitives
				(gr_poly
					(pts
						(arc
							(start -0.1778 -0.2794)
							(mid -0.249642 -0.249642)
							(end -0.2794 -0.1778)
						)
						(arc
							(start -0.2794 0.1778)
							(mid -0.249642 0.249642)
							(end -0.1778 0.2794)
						)
						(arc
							(start 0.1778 0.2794)
							(mid 0.249642 0.249642)
							(end 0.2794 0.1778)
						)
						(arc
							(start 0.2794 -0.1778)
							(mid 0.249642 -0.249642)
							(end 0.1778 -0.2794)
						)
					)
					(width 0)
					(fill yes)
				)
			)
		)
		(pad "2" smd custom
			(at 0 0.4445 90)
			(size 0.1397 0.1397)
			(layers "F.Cu" "F.Mask" "F.Paste")
			(net "JTAG_BMC_TRST_N")
			(options
				(clearance outline)
				(anchor circle)
			)
			(primitives
				(gr_poly
					(pts
						(arc
							(start -0.1778 -0.2794)
							(mid -0.249642 -0.249642)
							(end -0.2794 -0.1778)
						)
						(arc
							(start -0.2794 0.1778)
							(mid -0.249642 0.249642)
							(end -0.1778 0.2794)
						)
						(arc
							(start 0.1778 0.2794)
							(mid 0.249642 0.249642)
							(end 0.2794 0.1778)
						)
						(arc
							(start 0.2794 -0.1778)
							(mid 0.249642 -0.249642)
							(end 0.1778 -0.2794)
						)
					)
					(width 0)
					(fill yes)
				)
			)
		)
	)
	(footprint ""
		(layer "F.Cu")
		(at 344.424 -115.824 -90)
		(property "Reference" "PR10"
			(at 0 0 270)
			(layer "F.SilkS")
			(hide yes)
			(effects
				(font
					(size 1.27 1.27)
				)
			)
		)
		(property "Value" "54K9R2F-L-GP"
			(at 0.064008 -3.993896 270)
			(unlocked yes)
			(layer "F.Fab")
			(hide yes)
			(effects
				(font
					(size 1.016 1.016)
					(thickness 0.1524)
				)
			)
		)
		(property "Device Type" "R402H16"
			(at 0.064008 -5.517896 270)
			(unlocked yes)
			(layer "F.Fab")
			(hide yes)
			(effects
				(font
					(size 1.016 1.016)
					(thickness 0.1524)
				)
			)
		)
		(duplicate_pad_numbers_are_jumpers no)
		(fp_line
			(start -0.508 -0.9398)
			(end -0.508 0.9398)
			(stroke
				(width 0.1524)
				(type default)
			)
			(layer "F.SilkS")
		)
		(fp_line
			(start 0.508 -0.9398)
			(end -0.508 -0.9398)
			(stroke
				(width 0.1524)
				(type default)
			)
			(layer "F.SilkS")
		)
		(fp_rect
			(start -0.508 0.9398)
			(end 0.508 -0.9398)
			(stroke
				(width 0)
				(type default)
			)
			(fill no)
			(layer "F.CrtYd")
		)
		(fp_rect
			(start -0.508 0.9398)
			(end 0.508 -0.9398)
			(stroke
				(width 0)
				(type default)
			)
			(fill no)
			(layer "F.Fab")
		)
		(pad "1" smd custom
			(at 0 -0.4445 270)
			(size 0.1397 0.1397)
			(layers "F.Cu" "F.Mask" "F.Paste")
			(net "P5V_STBY_CC_R")
			(options
				(clearance outline)
				(anchor circle)
			)
			(primitives
				(gr_poly
					(pts
						(arc
							(start -0.1778 -0.2794)
							(mid -0.249642 -0.249642)
							(end -0.2794 -0.1778)
						)
						(arc
							(start -0.2794 0.1778)
							(mid -0.249642 0.249642)
							(end -0.1778 0.2794)
						)
						(arc
							(start 0.1778 0.2794)
							(mid 0.249642 0.249642)
							(end 0.2794 0.1778)
						)
						(arc
							(start 0.2794 -0.1778)
							(mid 0.249642 -0.249642)
							(end 0.1778 -0.2794)
						)
					)
					(width 0)
					(fill yes)
				)
			)
		)
		(pad "2" smd custom
			(at 0 0.4445 270)
			(size 0.1397 0.1397)
			(layers "F.Cu" "F.Mask" "F.Paste")
			(net "P5V_STBY_VFB")
			(options
				(clearance outline)
				(anchor circle)
			)
			(primitives
				(gr_poly
					(pts
						(arc
							(start -0.1778 -0.2794)
							(mid -0.249642 -0.249642)
							(end -0.2794 -0.1778)
						)
						(arc
							(start -0.2794 0.1778)
							(mid -0.249642 0.249642)
							(end -0.1778 0.2794)
						)
						(arc
							(start 0.1778 0.2794)
							(mid 0.249642 0.249642)
							(end 0.2794 0.1778)
						)
						(arc
							(start 0.2794 -0.1778)
							(mid 0.249642 -0.249642)
							(end 0.1778 -0.2794)
						)
					)
					(width 0)
					(fill yes)
				)
			)
		)
	)
	(footprint ""
		(layer "F.Cu")
		(at 238.1123 -114.9858 90)
		(property "Reference" "SR840"
			(at 0 0 90)
			(layer "F.SilkS")
			(hide yes)
			(effects
				(font
					(size 1.27 1.27)
				)
			)
		)
		(property "Value" "10KR2F-2-GP"
			(at 0.064008 -3.993896 90)
			(unlocked yes)
			(layer "F.Fab")
			(hide yes)
			(effects
				(font
					(size 1.016 1.016)
					(thickness 0.1524)
				)
			)
		)
		(property "Device Type" "R402H16"
			(at 0.064008 -5.517896 90)
			(unlocked yes)
			(layer "F.Fab")
			(hide yes)
			(effects
				(font
					(size 1.016 1.016)
					(thickness 0.1524)
				)
			)
		)
		(duplicate_pad_numbers_are_jumpers no)
		(fp_line
			(start 0.508 -0.9398)
			(end -0.508 -0.9398)
			(stroke
				(width 0.1524)
				(type default)
			)
			(layer "F.SilkS")
		)
		(fp_line
			(start -0.508 -0.9398)
			(end -0.508 0.9398)
			(stroke
				(width 0.1524)
				(type default)
			)
			(layer "F.SilkS")
		)
		(fp_rect
			(start -0.508 0.9398)
			(end 0.508 -0.9398)
			(stroke
				(width 0)
				(type default)
			)
			(fill no)
			(layer "F.CrtYd")
		)
		(fp_rect
			(start -0.508 0.9398)
			(end 0.508 -0.9398)
			(stroke
				(width 0)
				(type default)
			)
			(fill no)
			(layer "F.Fab")
		)
		(pad "1" smd custom
			(at 0 -0.4445 90)
			(size 0.1397 0.1397)
			(layers "F.Cu" "F.Mask" "F.Paste")
			(net "P1V8_E")
			(options
				(clearance outline)
				(anchor circle)
			)
			(primitives
				(gr_poly
					(pts
						(arc
							(start -0.1778 -0.2794)
							(mid -0.249642 -0.249642)
							(end -0.2794 -0.1778)
						)
						(arc
							(start -0.2794 0.1778)
							(mid -0.249642 0.249642)
							(end -0.1778 0.2794)
						)
						(arc
							(start 0.1778 0.2794)
							(mid 0.249642 0.249642)
							(end 0.2794 0.1778)
						)
						(arc
							(start 0.2794 -0.1778)
							(mid 0.249642 -0.249642)
							(end 0.1778 -0.2794)
						)
					)
					(width 0)
					(fill yes)
				)
			)
		)
		(pad "2" smd custom
			(at 0 0.4445 90)
			(size 0.1397 0.1397)
			(layers "F.Cu" "F.Mask" "F.Paste")
			(net "SMART_UART_EN")
			(options
				(clearance outline)
				(anchor circle)
			)
			(primitives
				(gr_poly
					(pts
						(arc
							(start -0.1778 -0.2794)
							(mid -0.249642 -0.249642)
							(end -0.2794 -0.1778)
						)
						(arc
							(start -0.2794 0.1778)
							(mid -0.249642 0.249642)
							(end -0.1778 0.2794)
						)
						(arc
							(start 0.1778 0.2794)
							(mid 0.249642 0.249642)
							(end 0.2794 0.1778)
						)
						(arc
							(start 0.2794 -0.1778)
							(mid 0.249642 -0.249642)
							(end 0.1778 -0.2794)
						)
					)
					(width 0)
					(fill yes)
				)
			)
		)
	)
	(footprint ""
		(layer "F.Cu")
		(at 310.896 -185.674 -90)
		(property "Reference" "SR943"
			(at 0 0 270)
			(layer "F.SilkS")
			(hide yes)
			(effects
				(font
					(size 1.27 1.27)
				)
			)
		)
		(property "Value" "4K75R2F-1-GP"
			(at 0.064008 -3.993896 270)
			(unlocked yes)
			(layer "F.Fab")
			(hide yes)
			(effects
				(font
					(size 1.016 1.016)
					(thickness 0.1524)
				)
			)
		)
		(property "Device Type" "R402H16"
			(at 0.064008 -5.517896 270)
			(unlocked yes)
			(layer "F.Fab")
			(hide yes)
			(effects
				(font
					(size 1.016 1.016)
					(thickness 0.1524)
				)
			)
		)
		(duplicate_pad_numbers_are_jumpers no)
		(fp_line
			(start -0.508 -0.9398)
			(end -0.508 0.9398)
			(stroke
				(width 0.1524)
				(type default)
			)
			(layer "F.SilkS")
		)
		(fp_line
			(start 0.508 -0.9398)
			(end -0.508 -0.9398)
			(stroke
				(width 0.1524)
				(type default)
			)
			(layer "F.SilkS")
		)
		(fp_rect
			(start -0.508 0.9398)
			(end 0.508 -0.9398)
			(stroke
				(width 0)
				(type default)
			)
			(fill no)
			(layer "F.CrtYd")
		)
		(fp_rect
			(start -0.508 0.9398)
			(end 0.508 -0.9398)
			(stroke
				(width 0)
				(type default)
			)
			(fill no)
			(layer "F.Fab")
		)
		(pad "1" smd custom
			(at 0 -0.4445 270)
			(size 0.1397 0.1397)
			(layers "F.Cu" "F.Mask" "F.Paste")
			(net "P3V3_STBY")
			(options
				(clearance outline)
				(anchor circle)
			)
			(primitives
				(gr_poly
					(pts
						(arc
							(start -0.1778 -0.2794)
							(mid -0.249642 -0.249642)
							(end -0.2794 -0.1778)
						)
						(arc
							(start -0.2794 0.1778)
							(mid -0.249642 0.249642)
							(end -0.1778 0.2794)
						)
						(arc
							(start 0.1778 0.2794)
							(mid 0.249642 0.249642)
							(end 0.2794 0.1778)
						)
						(arc
							(start 0.2794 -0.1778)
							(mid 0.249642 -0.249642)
							(end 0.1778 -0.2794)
						)
					)
					(width 0)
					(fill yes)
				)
			)
		)
		(pad "2" smd custom
			(at 0 0.4445 270)
			(size 0.1397 0.1397)
			(layers "F.Cu" "F.Mask" "F.Paste")
			(net "BMC_FW_DET_BOARD_VER_1")
			(options
				(clearance outline)
				(anchor circle)
			)
			(primitives
				(gr_poly
					(pts
						(arc
							(start -0.1778 -0.2794)
							(mid -0.249642 -0.249642)
							(end -0.2794 -0.1778)
						)
						(arc
							(start -0.2794 0.1778)
							(mid -0.249642 0.249642)
							(end -0.1778 0.2794)
						)
						(arc
							(start 0.1778 0.2794)
							(mid 0.249642 0.249642)
							(end 0.2794 0.1778)
						)
						(arc
							(start 0.2794 -0.1778)
							(mid 0.249642 -0.249642)
							(end 0.1778 -0.2794)
						)
					)
					(width 0)
					(fill yes)
				)
			)
		)
	)
	(footprint ""
		(layer "F.Cu")
		(at 204.793596 -116.097812 180)
		(property "Reference" "PR9008"
			(at 0 0 180)
			(layer "F.SilkS")
			(hide yes)
			(effects
				(font
					(size 1.27 1.27)
				)
			)
		)
		(property "Value" "2D2R3J-2-GP"
			(at -0.0254 -2.5146 180)
			(unlocked yes)
			(layer "F.Fab")
			(hide yes)
			(effects
				(font
					(size 1.016 1.016)
					(thickness 0.1524)
				)
			)
		)
		(property "Device Type" "R603H22"
			(at -0.0254 -4.0386 180)
			(unlocked yes)
			(layer "F.Fab")
			(hide yes)
			(effects
				(font
					(size 1.016 1.016)
					(thickness 0.1524)
				)
			)
		)
		(duplicate_pad_numbers_are_jumpers no)
		(fp_line
			(start 0.2032 0)
			(end 0.4826 0)
			(stroke
				(width 0.2032)
				(type default)
			)
			(layer "F.SilkS")
		)
		(fp_line
			(start -0.4826 0)
			(end -0.2032 0)
			(stroke
				(width 0.2032)
				(type default)
			)
			(layer "F.SilkS")
		)
		(fp_rect
			(start -0.5842 1.3335)
			(end 0.5842 -1.3335)
			(stroke
				(width 0)
				(type default)
			)
			(fill no)
			(layer "F.CrtYd")
		)
		(fp_rect
			(start -0.5842 1.3335)
			(end 0.5842 -1.3335)
			(stroke
				(width 0)
				(type default)
			)
			(fill no)
			(layer "F.Fab")
		)
		(pad "1" smd custom
			(at 0 -0.762 180)
			(size 0.2159 0.2159)
			(layers "F.Cu" "F.Mask" "F.Paste")
			(net "P1V5_E_VIN")
			(options
				(clearance outline)
				(anchor circle)
			)
			(primitives
				(gr_poly
					(pts
						(arc
							(start -0.3302 -0.4318)
							(mid -0.402042 -0.402042)
							(end -0.4318 -0.3302)
						)
						(arc
							(start -0.4318 0.3302)
							(mid -0.402042 0.402042)
							(end -0.3302 0.4318)
						)
						(arc
							(start 0.3302 0.4318)
							(mid 0.402042 0.402042)
							(end 0.4318 0.3302)
						)
						(arc
							(start 0.4318 -0.3302)
							(mid 0.402042 -0.402042)
							(end 0.3302 -0.4318)
						)
					)
					(width 0)
					(fill yes)
				)
			)
		)
		(pad "2" smd custom
			(at 0 0.762 180)
			(size 0.2159 0.2159)
			(layers "F.Cu" "F.Mask" "F.Paste")
			(net "P1V5_E_VCC")
			(options
				(clearance outline)
				(anchor circle)
			)
			(primitives
				(gr_poly
					(pts
						(arc
							(start -0.3302 -0.4318)
							(mid -0.402042 -0.402042)
							(end -0.4318 -0.3302)
						)
						(arc
							(start -0.4318 0.3302)
							(mid -0.402042 0.402042)
							(end -0.3302 0.4318)
						)
						(arc
							(start 0.3302 0.4318)
							(mid 0.402042 0.402042)
							(end 0.4318 0.3302)
						)
						(arc
							(start 0.4318 -0.3302)
							(mid 0.402042 -0.402042)
							(end 0.3302 -0.4318)
						)
					)
					(width 0)
					(fill yes)
				)
			)
		)
	)
	(footprint ""
		(layer "F.Cu")
		(at 281.178 -161.544)
		(property "Reference" "R258"
			(at 0 0 0)
			(layer "F.SilkS")
			(hide yes)
			(effects
				(font
					(size 1.27 1.27)
				)
			)
		)
		(property "Value" "100KR2F-L1-GP"
			(at 0.064008 -3.993896 0)
			(unlocked yes)
			(layer "F.Fab")
			(hide yes)
			(effects
				(font
					(size 1.016 1.016)
					(thickness 0.1524)
				)
			)
		)
		(property "Device Type" "R402H16"
			(at 0.064008 -5.517896 0)
			(unlocked yes)
			(layer "F.Fab")
			(hide yes)
			(effects
				(font
					(size 1.016 1.016)
					(thickness 0.1524)
				)
			)
		)
		(duplicate_pad_numbers_are_jumpers no)
		(fp_line
			(start -0.508 -0.9398)
			(end -0.508 0.9398)
			(stroke
				(width 0.1524)
				(type default)
			)
			(layer "F.SilkS")
		)
		(fp_line
			(start 0.508 -0.9398)
			(end -0.508 -0.9398)
			(stroke
				(width 0.1524)
				(type default)
			)
			(layer "F.SilkS")
		)
		(fp_rect
			(start -0.508 0.9398)
			(end 0.508 -0.9398)
			(stroke
				(width 0)
				(type default)
			)
			(fill no)
			(layer "F.CrtYd")
		)
		(fp_rect
			(start -0.508 0.9398)
			(end 0.508 -0.9398)
			(stroke
				(width 0)
				(type default)
			)
			(fill no)
			(layer "F.Fab")
		)
		(pad "1" smd custom
			(at 0 -0.4445)
			(size 0.1397 0.1397)
			(layers "F.Cu" "F.Mask" "F.Paste")
			(net "TP_LPC_CPU_FRAME_N")
			(options
				(clearance outline)
				(anchor circle)
			)
			(primitives
				(gr_poly
					(pts
						(arc
							(start -0.1778 -0.2794)
							(mid -0.249642 -0.249642)
							(end -0.2794 -0.1778)
						)
						(arc
							(start -0.2794 0.1778)
							(mid -0.249642 0.249642)
							(end -0.1778 0.2794)
						)
						(arc
							(start 0.1778 0.2794)
							(mid 0.249642 0.249642)
							(end 0.2794 0.1778)
						)
						(arc
							(start 0.2794 -0.1778)
							(mid 0.249642 -0.249642)
							(end 0.1778 -0.2794)
						)
					)
					(width 0)
					(fill yes)
				)
			)
		)
		(pad "2" smd custom
			(at 0 0.4445)
			(size 0.1397 0.1397)
			(layers "F.Cu" "F.Mask" "F.Paste")
			(net "GND")
			(options
				(clearance outline)
				(anchor circle)
			)
			(primitives
				(gr_poly
					(pts
						(arc
							(start -0.1778 -0.2794)
							(mid -0.249642 -0.249642)
							(end -0.2794 -0.1778)
						)
						(arc
							(start -0.2794 0.1778)
							(mid -0.249642 0.249642)
							(end -0.1778 0.2794)
						)
						(arc
							(start 0.1778 0.2794)
							(mid 0.249642 0.249642)
							(end 0.2794 0.1778)
						)
						(arc
							(start 0.2794 -0.1778)
							(mid 0.249642 -0.249642)
							(end 0.1778 -0.2794)
						)
					)
					(width 0)
					(fill yes)
				)
			)
		)
	)
)
